#ISCELL
  mstr_misc dns *
  *
#ISCELL
  mstr_symbols intel_corp_bpage *
  *
#CELL
  dev_discrete cap_a *
  page192_i1
#CELL
  dev_discrete cap_a *
  page192_i10
#CELL
  dev_discrete cap_a *
  page192_i11
#CELL
  dev_discrete cap_a *
  page192_i12
#CELL
  mstr_memory lcmxo2_a *
  page192_i14
#CELL
  dev_discrete cap_a *
  page192_i15
#CELL
  dev_discrete cap_a *
  page192_i16
#CELL
  dev_discrete cap_a *
  page192_i17
#CELL
  dev_discrete cap_a *
  page192_i18
#CELL
  dev_discrete cap_a *
  page192_i19
#ISCELL
  mstr_symbols gnd *
  page192_i2
#CELL
  dev_discrete cap_a *
  page192_i20
#CELL
  dev_discrete cap_a *
  page192_i21
#CELL
  dev_discrete cap_a *
  page192_i22
#CELL
  dev_discrete cap_a *
  page192_i23
#CELL
  dev_discrete cap_a *
  page192_i25
#ISCELL
  mstr_symbols gnd *
  page192_i26
#CELL
  dev_discrete cap_a *
  page192_i28
#ISCELL
  mstr_symbols p3v3_stby *
  page192_i29
#CELL
  dev_discrete cap_a *
  page192_i3
#ISCELL
  mstr_symbols p3v3_stby *
  page192_i30
#ISCELL
  mstr_symbols p3v3_stby *
  page192_i31
#ISCELL
  mstr_symbols p3v3_stby *
  page192_i32
#CELL
  mstr_discrete res *
  page192_i33
#CELL
  mstr_discrete res *
  page192_i34
#ISCELL
  mstr_symbols p3v3_stby *
  page192_i35
#ISCELL
  mstr_standard offpage *
  page192_i36
#ISCELL
  mstr_standard offpage *
  page192_i37
#CELL
  mstr_discrete res *
  page192_i38
#ISCELL
  mstr_symbols p3v3_stby *
  page192_i39
#CELL
  dev_discrete cap_a *
  page192_i4
#ISCELL
  mstr_standard offpage *
  page192_i40
#CELL
  mstr_discrete res *
  page192_i41
#ISCELL
  mstr_symbols p3v3_stby *
  page192_i42
#ISCELL
  mstr_standard offpage *
  page192_i45
#CELL
  mstr_discrete res *
  page192_i48
#CELL
  mstr_discrete res *
  page192_i49
#ISCELL
  mstr_symbols gnd *
  page192_i5
#ISCELL
  mstr_standard offpage *
  page192_i50
#ISCELL
  mstr_standard offpage *
  page192_i51
#ISCELL
  mstr_symbols pvpp_abc *
  page192_i52
#ISCELL
  mstr_standard offpage *
  page192_i54
#CELL
  mstr_discrete res *
  page192_i55
#ISCELL
  mstr_symbols p3v3_stby *
  page192_i56
#CELL
  mstr_discrete res *
  page192_i57
#ISCELL
  mstr_symbols p3v3_stby *
  page192_i58
#CELL
  mstr_discrete res *
  page192_i59
#CELL
  dev_discrete cap_a *
  page192_i6
#ISCELL
  mstr_standard offpage *
  page192_i60
#ISCELL
  mstr_symbols gnd *
  page192_i61
#ISCELL
  mstr_symbols pvpp_klm *
  page192_i62
#CELL
  dev_discrete cap_a *
  page192_i7
#CELL
  dev_discrete cap_a *
  page192_i8
#CELL
  dev_discrete cap_a *
  page192_i9
